# S9S_MB_2U (Grand Teton) — schematic netlist excerpt (pin names and nets, part order shuffled) for the footprints in the layout excerpt that follows; sources: Cadence DE-HDL packaged netlist, KiCad conversion of 03242023_DA0F0TMBIJ0_F0T_Motherboard_J_brd_V01_OCP.brd

U142  NC7SB3157  NC7SB3157P6X IC  pkg SMLF  page 197
  B1  = PECI_BMC_B1
  GND  = GND
  B0  = PECI_PCH_B1
  A  = PECI_CPU_GTL
  VCC  = P3V3_AUX
  S  = PECI_MUX_SEL_R

Q127  MOSFET_NCH_DUAL  PJT138K EMPTY  pkg SOT363XD  page 192
  S1  = GND
  G1  = P12V_E1S_EN_0_R
  D2  = P12V_E1S_UV_0_R
  S2  = GND
  G2  = P12V_E1S_0_EN_G
  D1  = P12V_E1S_0_EN_G

(kicad_pcb
	(version 20260206)
	(generator "pcbnew")
	(generator_version "10.0")
	(general
		(thickness 1.6)
		(legacy_teardrops no)
	)
	(paper "A4")
	(title_block
		(title "03242023_DA0F0TMBIJ0_F0T_Motherboard_J_brd_V01_OCP.brd")
		(comment 1 "Grand Teton / footprints 1516-1517 of 6105")
	)
	(layers
		(0 "F.Cu" signal "TOP")
		(4 "In1.Cu" signal "GND")
		(6 "In2.Cu" signal "IN1")
		(8 "In3.Cu" signal "GND1")
		(10 "In4.Cu" signal "IN2")
		(12 "In5.Cu" signal "GND2")
		(14 "In6.Cu" signal "IN3")
		(16 "In7.Cu" signal "GND3")
		(18 "In8.Cu" signal "VCC")
		(20 "In9.Cu" signal "VCC1")
		(22 "In10.Cu" signal "GND4")
		(24 "In11.Cu" signal "IN4")
		(26 "In12.Cu" signal "GND5")
		(28 "In13.Cu" signal "IN5")
		(30 "In14.Cu" signal "GND6")
		(32 "In15.Cu" signal "IN6")
		(34 "In16.Cu" signal "GND7")
		(2 "B.Cu" signal "BOTTOM")
		(9 "F.Adhes" user "F.Adhesive")
		(11 "B.Adhes" user "B.Adhesive")
		(13 "F.Paste" user "Package Geometry/Pastemask Top")
		(15 "B.Paste" user "Package Geometry/Pastemask Bottom")
		(5 "F.SilkS" user "Ref Des/Silkscreen Top")
		(7 "B.SilkS" user "Ref Des/Silkscreen Bottom")
		(1 "F.Mask" user "Board Geometry/Soldermask Top")
		(3 "B.Mask" user "Board Geometry/Soldermask Bottom")
		(17 "Dwgs.User" user "User.Drawings")
		(19 "Cmts.User" user "User.Comments")
		(21 "Eco1.User" user "User.Eco1")
		(23 "Eco2.User" user "User.Eco2")
		(25 "Edge.Cuts" user "Board Geometry/Outline")
		(27 "Margin" user)
		(31 "F.CrtYd" user "Package Geometry/Place Bound Top")
		(29 "B.CrtYd" user "Package Geometry/Place Bound Bottom")
		(35 "F.Fab" user "Ref Des/Assembly Top")
		(33 "B.Fab" user "Ref Des/Assembly Bottom")
	)
	(footprint ""
		(layer "F.Cu")
		(at 293.579042 -51.091338 90)
		(property "Reference" "Q127"
			(at 0.542036 -6.504432 0)
			(unlocked yes)
			(layer "F.SilkS")
			(effects
				(font
					(size 0.7874 0.5842)
					(thickness 0.1524)
				)
				(justify left)
			)
		)
		(property "Value" ""
			(at 0 0 90)
			(layer "F.Fab")
			(effects
				(font
					(size 1.27 1.27)
				)
			)
		)
		(duplicate_pad_numbers_are_jumpers no)
		(fp_line
			(start 1.332738 -1.100074)
			(end 1.332738 1.100074)
			(stroke
				(width 0.1524)
				(type default)
			)
			(layer "F.SilkS")
		)
		(fp_line
			(start 0.4826 -1.100074)
			(end 1.332738 -1.100074)
			(stroke
				(width 0.1524)
				(type default)
			)
			(layer "F.SilkS")
		)
		(fp_line
			(start -0.4826 -1.100074)
			(end 0 -0.541274)
			(stroke
				(width 0.1524)
				(type default)
			)
			(layer "F.SilkS")
		)
		(fp_line
			(start -1.332738 -1.100074)
			(end -0.4826 -1.100074)
			(stroke
				(width 0.1524)
				(type default)
			)
			(layer "F.SilkS")
		)
		(fp_line
			(start 0 -0.541274)
			(end 0.4826 -1.100074)
			(stroke
				(width 0.1524)
				(type default)
			)
			(layer "F.SilkS")
		)
		(fp_line
			(start 1.332738 1.100074)
			(end -1.332738 1.100074)
			(stroke
				(width 0.1524)
				(type default)
			)
			(layer "F.SilkS")
		)
		(fp_line
			(start -1.332738 1.100074)
			(end -1.332738 -1.100074)
			(stroke
				(width 0.1524)
				(type default)
			)
			(layer "F.SilkS")
		)
		(fp_poly
			(pts
				(xy -2.43332 -1.270254) (xy -1.731264 -0.919226) (xy -2.43332 -0.568198)
			)
			(stroke
				(width 0)
				(type default)
			)
			(fill yes)
			(layer "F.SilkS")
		)
		(fp_line
			(start 0.674878 -1.100074)
			(end 0.674878 1.100074)
			(stroke
				(width 0.1)
				(type default)
			)
			(layer "F.Fab")
		)
		(fp_line
			(start -0.674878 -1.100074)
			(end 0.674878 -1.100074)
			(stroke
				(width 0.1)
				(type default)
			)
			(layer "F.Fab")
		)
		(fp_line
			(start 0.674878 1.100074)
			(end -0.674878 1.100074)
			(stroke
				(width 0.1)
				(type default)
			)
			(layer "F.Fab")
		)
		(fp_line
			(start -0.674878 1.100074)
			(end -0.674878 -1.100074)
			(stroke
				(width 0.1)
				(type default)
			)
			(layer "F.Fab")
		)
		(fp_poly
			(pts
				(xy -2.2352 -0.298958) (xy -2.2352 -1.001014) (xy -1.533144 -0.649986)
			)
			(stroke
				(width 0)
				(type default)
			)
			(fill yes)
			(layer "F.Fab")
		)
		(pad "1" smd rect
			(at -0.94996 -0.649986 180)
			(size 0.4318 0.508)
			(layers "F.Cu" "F.Mask" "F.Paste")
			(net "GND")
		)
		(pad "2" smd rect
			(at -0.94996 0 180)
			(size 0.4318 0.508)
			(layers "F.Cu" "F.Mask" "F.Paste")
			(net "P12V_E1S_EN_0_R")
		)
		(pad "3" smd rect
			(at -0.94996 0.649986 180)
			(size 0.4318 0.508)
			(layers "F.Cu" "F.Mask" "F.Paste")
			(net "P12V_E1S_UV_0_R")
		)
		(pad "4" smd rect
			(at 0.94996 0.649986 180)
			(size 0.4318 0.508)
			(layers "F.Cu" "F.Mask" "F.Paste")
			(net "GND")
		)
		(pad "5" smd rect
			(at 0.94996 0 180)
			(size 0.4318 0.508)
			(layers "F.Cu" "F.Mask" "F.Paste")
			(net "P12V_E1S_0_EN_G")
		)
		(pad "6" smd rect
			(at 0.94996 -0.649986 180)
			(size 0.4318 0.508)
			(layers "F.Cu" "F.Mask" "F.Paste")
			(net "P12V_E1S_0_EN_G")
		)
	)
	(footprint ""
		(layer "F.Cu")
		(at 307.361336 -59.037728 90)
		(property "Reference" "U142"
			(at -0.091186 3.191764 0)
			(unlocked yes)
			(layer "F.SilkS")
			(effects
				(font
					(size 0.7874 0.5842)
					(thickness 0.1524)
				)
			)
		)
		(property "Value" ""
			(at 0 0 90)
			(layer "F.Fab")
			(effects
				(font
					(size 1.27 1.27)
				)
			)
		)
		(duplicate_pad_numbers_are_jumpers no)
		(fp_line
			(start 1.7272 -1.1176)
			(end 0.254 -1.1176)
			(stroke
				(width 0.1524)
				(type default)
			)
			(layer "F.SilkS")
		)
		(fp_line
			(start 1.7272 -1.1176)
			(end 1.7272 1.1176)
			(stroke
				(width 0.1524)
				(type default)
			)
			(layer "F.SilkS")
		)
		(fp_line
			(start 0.254 -1.1176)
			(end 0 -0.7366)
			(stroke
				(width 0.1524)
				(type default)
			)
			(layer "F.SilkS")
		)
		(fp_line
			(start -0.254 -1.1176)
			(end -1.7272 -1.1176)
			(stroke
				(width 0.1524)
				(type default)
			)
			(layer "F.SilkS")
		)
		(fp_line
			(start 0 -0.7366)
			(end -0.254 -1.1176)
			(stroke
				(width 0.1524)
				(type default)
			)
			(layer "F.SilkS")
		)
		(fp_line
			(start 1.7272 1.1176)
			(end -1.7272 1.1176)
			(stroke
				(width 0.1524)
				(type default)
			)
			(layer "F.SilkS")
		)
		(fp_line
			(start -1.7272 1.1176)
			(end -1.7272 -1.1176)
			(stroke
				(width 0.1524)
				(type default)
			)
			(layer "F.SilkS")
		)
		(fp_poly
			(pts
				(xy -1.31953 -1.375156) (xy -1.70053 -2.137156) (xy -0.93853 -2.137156)
			)
			(stroke
				(width 0)
				(type default)
			)
			(fill yes)
			(layer "F.SilkS")
		)
		(fp_line
			(start 1.5748 -1.1176)
			(end -1.5748 -1.1176)
			(stroke
				(width 0.1)
				(type default)
			)
			(layer "F.Fab")
		)
		(fp_line
			(start -1.5748 -1.1176)
			(end -1.5748 1.1176)
			(stroke
				(width 0.1)
				(type default)
			)
			(layer "F.Fab")
		)
		(fp_line
			(start 1.5748 1.1176)
			(end 1.5748 -1.1176)
			(stroke
				(width 0.1)
				(type default)
			)
			(layer "F.Fab")
		)
		(fp_line
			(start -1.5748 1.1176)
			(end 1.5748 1.1176)
			(stroke
				(width 0.1)
				(type default)
			)
			(layer "F.Fab")
		)
		(fp_poly
			(pts
				(xy -1.9558 -0.649986) (xy -2.7178 -0.268986) (xy -2.7178 -1.030986)
			)
			(stroke
				(width 0)
				(type default)
			)
			(fill yes)
			(layer "F.Fab")
		)
		(pad "1" smd rect
			(at -0.999998 -0.649986)
			(size 0.3556 1.1176)
			(layers "F.Cu" "F.Mask" "F.Paste")
			(net "PECI_BMC_B1")
		)
		(pad "2" smd rect
			(at -0.999998 0)
			(size 0.3556 1.1176)
			(layers "F.Cu" "F.Mask" "F.Paste")
			(net "GND")
		)
		(pad "3" smd rect
			(at -0.999998 0.649986)
			(size 0.3556 1.1176)
			(layers "F.Cu" "F.Mask" "F.Paste")
			(net "PECI_PCH_B1")
		)
		(pad "4" smd rect
			(at 0.999998 0.649986)
			(size 0.3556 1.1176)
			(layers "F.Cu" "F.Mask" "F.Paste")
			(net "PECI_CPU_GTL")
		)
		(pad "5" smd rect
			(at 0.999998 0)
			(size 0.3556 1.1176)
			(layers "F.Cu" "F.Mask" "F.Paste")
			(net "P3V3_AUX")
		)
		(pad "6" smd rect
			(at 0.999998 -0.649986)
			(size 0.3556 1.1176)
			(layers "F.Cu" "F.Mask" "F.Paste")
			(net "PECI_MUX_SEL_R")
		)
	)
)
